(kicad_pcb
	(version 20260206)
	(generator "pcbnew")
	(generator_version "10.0")
	(general
		(thickness 1.6)
		(legacy_teardrops no)
	)
	(paper "A4")
	(title_block
		(title "panther-plus-userver — 13130-1b_20150205.brd")
		(comment 1 "Honey Badger (Wiwynn) / footprints 1320-1328 of 1509")
	)
	(layers
		(0 "F.Cu" signal "TOP")
		(4 "In1.Cu" signal "L2")
		(6 "In2.Cu" signal "L3")
		(8 "In3.Cu" signal "L4")
		(10 "In4.Cu" signal "L5")
		(12 "In5.Cu" signal "L6")
		(14 "In6.Cu" signal "L7")
		(16 "In7.Cu" signal "L8")
		(18 "In8.Cu" signal "L9")
		(20 "In9.Cu" signal "L10")
		(22 "In10.Cu" signal "L11")
		(2 "B.Cu" signal "BOTTOM")
		(9 "F.Adhes" user "F.Adhesive")
		(11 "B.Adhes" user "B.Adhesive")
		(13 "F.Paste" user "Package Geometry/Pastemask Top")
		(15 "B.Paste" user "Package Geometry/Pastemask Bottom")
		(5 "F.SilkS" user "Ref Des/Silkscreen Top")
		(7 "B.SilkS" user "Ref Des/Silkscreen Bottom")
		(1 "F.Mask" user "Board Geometry/Soldermask Top")
		(3 "B.Mask" user "Board Geometry/Soldermask Bottom")
		(17 "Dwgs.User" user "User.Drawings")
		(19 "Cmts.User" user "User.Comments")
		(21 "Eco1.User" user "User.Eco1")
		(23 "Eco2.User" user "User.Eco2")
		(25 "Edge.Cuts" user "Board Geometry/Outline")
		(27 "Margin" user)
		(31 "F.CrtYd" user "Package Geometry/Place Bound Top")
		(29 "B.CrtYd" user "Package Geometry/Place Bound Bottom")
		(35 "F.Fab" user "Ref Des/Assembly Top")
		(33 "B.Fab" user "Ref Des/Assembly Bottom")
	)
	(footprint ""
		(layer "B.Cu")
		(at 92.3544 -30.861 90)
		(property "Reference" "C229"
			(at 0 0 90)
			(layer "B.SilkS")
			(hide yes)
			(effects
				(font
					(size 1.27 1.27)
				)
				(justify mirror)
			)
		)
		(property "Value" "SC1U10V2KX-1GP"
			(at -1.1811 -2.7051 90)
			(unlocked yes)
			(layer "B.Fab")
			(hide yes)
			(effects
				(font
					(size 1.016 1.016)
					(thickness 0.1524)
				)
				(justify mirror)
			)
		)
		(property "Device Type" "C402H22"
			(at -1.1811 -4.2291 90)
			(unlocked yes)
			(layer "B.Fab")
			(hide yes)
			(effects
				(font
					(size 1.016 1.016)
					(thickness 0.1524)
				)
				(justify mirror)
			)
		)
		(duplicate_pad_numbers_are_jumpers no)
		(fp_rect
			(start 0.381 0.7366)
			(end -0.381 -0.7366)
			(stroke
				(width 0)
				(type default)
			)
			(fill no)
			(layer "B.CrtYd")
		)
		(fp_rect
			(start 0.381 0.7366)
			(end -0.381 -0.7366)
			(stroke
				(width 0)
				(type default)
			)
			(fill no)
			(layer "B.Fab")
		)
		(pad "1" smd custom
			(at 0 -0.4572 270)
			(size 0.1143 0.1143)
			(layers "B.Cu" "B.Mask" "B.Paste")
			(net "P1V0")
			(options
				(clearance outline)
				(anchor circle)
			)
			(primitives
				(gr_poly
					(pts
						(arc
							(start -0.254 0.1778)
							(mid -0.239121 0.213721)
							(end -0.2032 0.2286)
						)
						(arc
							(start 0.2032 0.2286)
							(mid 0.239121 0.213721)
							(end 0.254 0.1778)
						)
						(arc
							(start 0.254 -0.1778)
							(mid 0.239121 -0.213721)
							(end 0.2032 -0.2286)
						)
						(arc
							(start -0.2032 -0.2286)
							(mid -0.239121 -0.213721)
							(end -0.254 -0.1778)
						)
					)
					(width 0)
					(fill yes)
				)
			)
		)
		(pad "2" smd custom
			(at 0 0.4572 270)
			(size 0.1143 0.1143)
			(layers "B.Cu" "B.Mask" "B.Paste")
			(net "GND")
			(options
				(clearance outline)
				(anchor circle)
			)
			(primitives
				(gr_poly
					(pts
						(arc
							(start -0.254 0.1778)
							(mid -0.239121 0.213721)
							(end -0.2032 0.2286)
						)
						(arc
							(start 0.2032 0.2286)
							(mid 0.239121 0.213721)
							(end 0.254 0.1778)
						)
						(arc
							(start 0.254 -0.1778)
							(mid 0.239121 -0.213721)
							(end 0.2032 -0.2286)
						)
						(arc
							(start -0.2032 -0.2286)
							(mid -0.239121 -0.213721)
							(end -0.254 -0.1778)
						)
					)
					(width 0)
					(fill yes)
				)
			)
		)
	)
	(footprint ""
		(layer "B.Cu")
		(at 18.796 -57.9882)
		(property "Reference" "PR1"
			(at 0 0 0)
			(layer "B.SilkS")
			(hide yes)
			(effects
				(font
					(size 1.27 1.27)
				)
				(justify mirror)
			)
		)
		(property "Value" "100R3F-1-GP"
			(at 0.0254 -2.0193 0)
			(unlocked yes)
			(layer "B.Fab")
			(hide yes)
			(effects
				(font
					(size 1.016 1.016)
					(thickness 0.1524)
				)
				(justify mirror)
			)
		)
		(property "Device Type" "R603H22"
			(at 0.0254 -3.5433 0)
			(unlocked yes)
			(layer "B.Fab")
			(hide yes)
			(effects
				(font
					(size 1.016 1.016)
					(thickness 0.1524)
				)
				(justify mirror)
			)
		)
		(duplicate_pad_numbers_are_jumpers no)
		(fp_line
			(start -0.4318 0)
			(end -0.2032 0)
			(stroke
				(width 0.2032)
				(type default)
			)
			(layer "B.SilkS")
		)
		(fp_line
			(start 0.2032 0)
			(end 0.4191 0)
			(stroke
				(width 0.2032)
				(type default)
			)
			(layer "B.SilkS")
		)
		(fp_rect
			(start 0.635 1.1811)
			(end -0.635 -1.1811)
			(stroke
				(width 0)
				(type default)
			)
			(fill no)
			(layer "B.CrtYd")
		)
		(fp_rect
			(start 0.635 1.1811)
			(end -0.635 -1.1811)
			(stroke
				(width 0)
				(type default)
			)
			(fill no)
			(layer "B.Fab")
		)
		(pad "1" smd custom
			(at 0 -0.6604 180)
			(size 0.19685 0.19685)
			(layers "B.Cu" "B.Mask" "B.Paste")
			(net "VR_PVNN_FB")
			(options
				(clearance outline)
				(anchor circle)
			)
			(primitives
				(gr_poly
					(pts
						(arc
							(start 0.508 0.2921)
							(mid 0.478242 0.363942)
							(end 0.4064 0.3937)
						)
						(arc
							(start -0.4064 0.3937)
							(mid -0.478242 0.363942)
							(end -0.508 0.2921)
						)
						(arc
							(start -0.508 -0.2921)
							(mid -0.478242 -0.363942)
							(end -0.4064 -0.3937)
						)
						(arc
							(start 0.4064 -0.3937)
							(mid 0.478242 -0.363942)
							(end 0.508 -0.2921)
						)
					)
					(width 0)
					(fill yes)
				)
			)
		)
		(pad "2" smd custom
			(at 0 0.6604 180)
			(size 0.19685 0.19685)
			(layers "B.Cu" "B.Mask" "B.Paste")
			(net "VR_PVNN_FB_RC1")
			(options
				(clearance outline)
				(anchor circle)
			)
			(primitives
				(gr_poly
					(pts
						(arc
							(start 0.508 0.2921)
							(mid 0.478242 0.363942)
							(end 0.4064 0.3937)
						)
						(arc
							(start -0.4064 0.3937)
							(mid -0.478242 0.363942)
							(end -0.508 0.2921)
						)
						(arc
							(start -0.508 -0.2921)
							(mid -0.478242 -0.363942)
							(end -0.4064 -0.3937)
						)
						(arc
							(start 0.4064 -0.3937)
							(mid 0.478242 -0.363942)
							(end 0.508 -0.2921)
						)
					)
					(width 0)
					(fill yes)
				)
			)
		)
	)
	(footprint ""
		(layer "B.Cu")
		(at 107.696 -19.939 -90)
		(property "Reference" "L8"
			(at 0 0 90)
			(layer "B.SilkS")
			(hide yes)
			(effects
				(font
					(size 1.27 1.27)
				)
				(justify mirror)
			)
		)
		(property "Value" "BLM18PG121SN1D-GP"
			(at 0.0254 -2.8956 270)
			(unlocked yes)
			(layer "B.Fab")
			(hide yes)
			(effects
				(font
					(size 1.016 1.016)
					(thickness 0.1524)
				)
				(justify mirror)
			)
		)
		(property "Device Type" "L1608-UH38"
			(at 0.0254 -4.4196 270)
			(unlocked yes)
			(layer "B.Fab")
			(hide yes)
			(effects
				(font
					(size 1.016 1.016)
					(thickness 0.1524)
				)
				(justify mirror)
			)
		)
		(duplicate_pad_numbers_are_jumpers no)
		(fp_line
			(start 0.4064 0)
			(end -0.4064 0)
			(stroke
				(width 0.2032)
				(type default)
			)
			(layer "B.SilkS")
		)
		(fp_rect
			(start 0.635 1.1811)
			(end -0.635 -1.1811)
			(stroke
				(width 0)
				(type default)
			)
			(fill no)
			(layer "B.CrtYd")
		)
		(fp_rect
			(start 0.635 1.1811)
			(end -0.635 -1.1811)
			(stroke
				(width 0)
				(type default)
			)
			(fill no)
			(layer "B.Fab")
		)
		(pad "1" smd custom
			(at 0 -0.6604 90)
			(size 0.19685 0.19685)
			(layers "B.Cu" "B.Mask" "B.Paste")
			(net "PV_VDDR")
			(options
				(clearance outline)
				(anchor circle)
			)
			(primitives
				(gr_poly
					(pts
						(arc
							(start 0.508 0.2921)
							(mid 0.478242 0.363942)
							(end 0.4064 0.3937)
						)
						(arc
							(start -0.4064 0.3937)
							(mid -0.478242 0.363942)
							(end -0.508 0.2921)
						)
						(arc
							(start -0.508 -0.2921)
							(mid -0.478242 -0.363942)
							(end -0.4064 -0.3937)
						)
						(arc
							(start 0.4064 -0.3937)
							(mid 0.478242 -0.363942)
							(end 0.508 -0.2921)
						)
					)
					(width 0)
					(fill yes)
				)
			)
		)
		(pad "2" smd custom
			(at 0 0.6604 90)
			(size 0.19685 0.19685)
			(layers "B.Cu" "B.Mask" "B.Paste")
			(net "VCCCLKDDR1")
			(options
				(clearance outline)
				(anchor circle)
			)
			(primitives
				(gr_poly
					(pts
						(arc
							(start 0.508 0.2921)
							(mid 0.478242 0.363942)
							(end 0.4064 0.3937)
						)
						(arc
							(start -0.4064 0.3937)
							(mid -0.478242 0.363942)
							(end -0.508 0.2921)
						)
						(arc
							(start -0.508 -0.2921)
							(mid -0.478242 -0.363942)
							(end -0.4064 -0.3937)
						)
						(arc
							(start 0.4064 -0.3937)
							(mid 0.478242 -0.363942)
							(end 0.508 -0.2921)
						)
					)
					(width 0)
					(fill yes)
				)
			)
		)
	)
	(footprint ""
		(layer "B.Cu")
		(at 71.247 -53.467 180)
		(property "Reference" "R262"
			(at 0 0 0)
			(layer "B.SilkS")
			(hide yes)
			(effects
				(font
					(size 1.27 1.27)
				)
				(justify mirror)
			)
		)
		(property "Value" "0R2J-2-GP"
			(at -0.064008 -3.993896 180)
			(unlocked yes)
			(layer "B.Fab")
			(hide yes)
			(effects
				(font
					(size 1.016 1.016)
					(thickness 0.1524)
				)
				(justify mirror)
			)
		)
		(property "Device Type" "R402H16"
			(at -0.064008 -5.517896 180)
			(unlocked yes)
			(layer "B.Fab")
			(hide yes)
			(effects
				(font
					(size 1.016 1.016)
					(thickness 0.1524)
				)
				(justify mirror)
			)
		)
		(duplicate_pad_numbers_are_jumpers no)
		(fp_rect
			(start 0.381 0.8382)
			(end -0.381 -0.8382)
			(stroke
				(width 0)
				(type default)
			)
			(fill no)
			(layer "B.CrtYd")
		)
		(fp_rect
			(start 0.381 0.8382)
			(end -0.381 -0.8382)
			(stroke
				(width 0)
				(type default)
			)
			(fill no)
			(layer "B.Fab")
		)
		(pad "1" smd custom
			(at 0 -0.4318)
			(size 0.127 0.127)
			(layers "B.Cu" "B.Mask" "B.Paste")
			(net "MEMORY_HOT_LV_R#")
			(options
				(clearance outline)
				(anchor circle)
			)
			(primitives
				(gr_poly
					(pts
						(arc
							(start -0.2032 0.2794)
							(mid -0.239121 0.264521)
							(end -0.254 0.2286)
						)
						(arc
							(start -0.254 -0.2286)
							(mid -0.239121 -0.264521)
							(end -0.2032 -0.2794)
						)
						(arc
							(start 0.2032 -0.2794)
							(mid 0.239121 -0.264521)
							(end 0.254 -0.2286)
						)
						(arc
							(start 0.254 0.2286)
							(mid 0.239121 0.264521)
							(end 0.2032 0.2794)
						)
					)
					(width 0)
					(fill yes)
				)
			)
		)
		(pad "2" smd custom
			(at 0 0.4318)
			(size 0.127 0.127)
			(layers "B.Cu" "B.Mask" "B.Paste")
			(net "MEMORY_HOT_LV_E1#")
			(options
				(clearance outline)
				(anchor circle)
			)
			(primitives
				(gr_poly
					(pts
						(arc
							(start -0.2032 0.2794)
							(mid -0.239121 0.264521)
							(end -0.254 0.2286)
						)
						(arc
							(start -0.254 -0.2286)
							(mid -0.239121 -0.264521)
							(end -0.2032 -0.2794)
						)
						(arc
							(start 0.2032 -0.2794)
							(mid 0.239121 -0.264521)
							(end 0.254 -0.2286)
						)
						(arc
							(start 0.254 0.2286)
							(mid 0.239121 0.264521)
							(end 0.2032 0.2794)
						)
					)
					(width 0)
					(fill yes)
				)
			)
		)
	)
	(footprint ""
		(layer "B.Cu")
		(at 177.292 -42.545 180)
		(property "Reference" "R177"
			(at 0 0 0)
			(layer "B.SilkS")
			(hide yes)
			(effects
				(font
					(size 1.27 1.27)
				)
				(justify mirror)
			)
		)
		(property "Value" "10KR2F-2-GP"
			(at -1.7907 -1.1176 180)
			(unlocked yes)
			(layer "B.Fab")
			(hide yes)
			(effects
				(font
					(size 1.016 1.016)
					(thickness 0.1524)
				)
				(justify mirror)
			)
		)
		(property "Device Type" "R402H16"
			(at -1.7907 -2.6416 180)
			(unlocked yes)
			(layer "B.Fab")
			(hide yes)
			(effects
				(font
					(size 1.016 1.016)
					(thickness 0.1524)
				)
				(justify mirror)
			)
		)
		(duplicate_pad_numbers_are_jumpers no)
		(fp_rect
			(start 0.381 0.8382)
			(end -0.381 -0.8382)
			(stroke
				(width 0)
				(type default)
			)
			(fill no)
			(layer "B.CrtYd")
		)
		(fp_rect
			(start 0.381 0.8382)
			(end -0.381 -0.8382)
			(stroke
				(width 0)
				(type default)
			)
			(fill no)
			(layer "B.Fab")
		)
		(pad "1" smd custom
			(at 0 -0.4318)
			(size 0.127 0.127)
			(layers "B.Cu" "B.Mask" "B.Paste")
			(net "P3V3_STBY")
			(options
				(clearance outline)
				(anchor circle)
			)
			(primitives
				(gr_poly
					(pts
						(arc
							(start -0.2032 0.2794)
							(mid -0.239121 0.264521)
							(end -0.254 0.2286)
						)
						(arc
							(start -0.254 -0.2286)
							(mid -0.239121 -0.264521)
							(end -0.2032 -0.2794)
						)
						(arc
							(start 0.2032 -0.2794)
							(mid 0.239121 -0.264521)
							(end 0.254 -0.2286)
						)
						(arc
							(start 0.254 0.2286)
							(mid 0.239121 0.264521)
							(end 0.2032 0.2794)
						)
					)
					(width 0)
					(fill yes)
				)
			)
		)
		(pad "2" smd custom
			(at 0 0.4318)
			(size 0.127 0.127)
			(layers "B.Cu" "B.Mask" "B.Paste")
			(net "SPI_SW_RST#")
			(options
				(clearance outline)
				(anchor circle)
			)
			(primitives
				(gr_poly
					(pts
						(arc
							(start -0.2032 0.2794)
							(mid -0.239121 0.264521)
							(end -0.254 0.2286)
						)
						(arc
							(start -0.254 -0.2286)
							(mid -0.239121 -0.264521)
							(end -0.2032 -0.2794)
						)
						(arc
							(start 0.2032 -0.2794)
							(mid 0.239121 -0.264521)
							(end 0.254 -0.2286)
						)
						(arc
							(start 0.254 0.2286)
							(mid 0.239121 0.264521)
							(end 0.2032 0.2794)
						)
					)
					(width 0)
					(fill yes)
				)
			)
		)
	)
	(footprint ""
		(layer "B.Cu")
		(at 6.223 -35.179 90)
		(property "Reference" "PC185"
			(at 0 0 90)
			(layer "B.SilkS")
			(hide yes)
			(effects
				(font
					(size 1.27 1.27)
				)
				(justify mirror)
			)
		)
		(property "Value" "SC1U10V2KX-1GP"
			(at -1.8923 -1.2065 90)
			(unlocked yes)
			(layer "B.Fab")
			(hide yes)
			(effects
				(font
					(size 1.016 1.016)
					(thickness 0.1524)
				)
				(justify mirror)
			)
		)
		(property "Device Type" "C402H22"
			(at -1.8923 -2.7305 90)
			(unlocked yes)
			(layer "B.Fab")
			(hide yes)
			(effects
				(font
					(size 1.016 1.016)
					(thickness 0.1524)
				)
				(justify mirror)
			)
		)
		(duplicate_pad_numbers_are_jumpers no)
		(fp_rect
			(start 0.381 0.7366)
			(end -0.381 -0.7366)
			(stroke
				(width 0)
				(type default)
			)
			(fill no)
			(layer "B.CrtYd")
		)
		(fp_rect
			(start 0.381 0.7366)
			(end -0.381 -0.7366)
			(stroke
				(width 0)
				(type default)
			)
			(fill no)
			(layer "B.Fab")
		)
		(pad "1" smd custom
			(at 0 -0.4572 270)
			(size 0.1143 0.1143)
			(layers "B.Cu" "B.Mask" "B.Paste")
			(net "GND")
			(options
				(clearance outline)
				(anchor circle)
			)
			(primitives
				(gr_poly
					(pts
						(arc
							(start -0.254 0.1778)
							(mid -0.239121 0.213721)
							(end -0.2032 0.2286)
						)
						(arc
							(start 0.2032 0.2286)
							(mid 0.239121 0.213721)
							(end 0.254 0.1778)
						)
						(arc
							(start 0.254 -0.1778)
							(mid 0.239121 -0.213721)
							(end 0.2032 -0.2286)
						)
						(arc
							(start -0.2032 -0.2286)
							(mid -0.239121 -0.213721)
							(end -0.254 -0.1778)
						)
					)
					(width 0)
					(fill yes)
				)
			)
		)
		(pad "2" smd custom
			(at 0 0.4572 270)
			(size 0.1143 0.1143)
			(layers "B.Cu" "B.Mask" "B.Paste")
			(net "P3V3_STBY_VREG")
			(options
				(clearance outline)
				(anchor circle)
			)
			(primitives
				(gr_poly
					(pts
						(arc
							(start -0.254 0.1778)
							(mid -0.239121 0.213721)
							(end -0.2032 0.2286)
						)
						(arc
							(start 0.2032 0.2286)
							(mid 0.239121 0.213721)
							(end 0.254 0.1778)
						)
						(arc
							(start 0.254 -0.1778)
							(mid 0.239121 -0.213721)
							(end 0.2032 -0.2286)
						)
						(arc
							(start -0.2032 -0.2286)
							(mid -0.239121 -0.213721)
							(end -0.254 -0.1778)
						)
					)
					(width 0)
					(fill yes)
				)
			)
		)
	)
	(footprint ""
		(layer "B.Cu")
		(at 71.9074 -22.8092)
		(property "Reference" "PR171"
			(at 0 0 0)
			(layer "B.SilkS")
			(hide yes)
			(effects
				(font
					(size 1.27 1.27)
				)
				(justify mirror)
			)
		)
		(property "Value" "0R2J-2-GP"
			(at -1.7907 -1.1176 0)
			(unlocked yes)
			(layer "B.Fab")
			(hide yes)
			(effects
				(font
					(size 1.016 1.016)
					(thickness 0.1524)
				)
				(justify mirror)
			)
		)
		(property "Device Type" "R402H16"
			(at -1.7907 -2.6416 0)
			(unlocked yes)
			(layer "B.Fab")
			(hide yes)
			(effects
				(font
					(size 1.016 1.016)
					(thickness 0.1524)
				)
				(justify mirror)
			)
		)
		(duplicate_pad_numbers_are_jumpers no)
		(fp_rect
			(start 0.381 0.8382)
			(end -0.381 -0.8382)
			(stroke
				(width 0)
				(type default)
			)
			(fill no)
			(layer "B.CrtYd")
		)
		(fp_rect
			(start 0.381 0.8382)
			(end -0.381 -0.8382)
			(stroke
				(width 0)
				(type default)
			)
			(fill no)
			(layer "B.Fab")
		)
		(pad "1" smd custom
			(at 0 -0.4318 180)
			(size 0.127 0.127)
			(layers "B.Cu" "B.Mask" "B.Paste")
			(net "P3V3_STBY_PG")
			(options
				(clearance outline)
				(anchor circle)
			)
			(primitives
				(gr_poly
					(pts
						(arc
							(start -0.2032 0.2794)
							(mid -0.239121 0.264521)
							(end -0.254 0.2286)
						)
						(arc
							(start -0.254 -0.2286)
							(mid -0.239121 -0.264521)
							(end -0.2032 -0.2794)
						)
						(arc
							(start 0.2032 -0.2794)
							(mid 0.239121 -0.264521)
							(end 0.254 -0.2286)
						)
						(arc
							(start 0.254 0.2286)
							(mid 0.239121 0.264521)
							(end 0.2032 0.2794)
						)
					)
					(width 0)
					(fill yes)
				)
			)
		)
		(pad "2" smd custom
			(at 0 0.4318 180)
			(size 0.127 0.127)
			(layers "B.Cu" "B.Mask" "B.Paste")
			(net "VR_EN_P1V8_STBY")
			(options
				(clearance outline)
				(anchor circle)
			)
			(primitives
				(gr_poly
					(pts
						(arc
							(start -0.2032 0.2794)
							(mid -0.239121 0.264521)
							(end -0.254 0.2286)
						)
						(arc
							(start -0.254 -0.2286)
							(mid -0.239121 -0.264521)
							(end -0.2032 -0.2794)
						)
						(arc
							(start 0.2032 -0.2794)
							(mid 0.239121 -0.264521)
							(end 0.254 -0.2286)
						)
						(arc
							(start 0.254 0.2286)
							(mid 0.239121 0.264521)
							(end 0.2032 0.2794)
						)
					)
					(width 0)
					(fill yes)
				)
			)
		)
	)
	(footprint ""
		(layer "B.Cu")
		(at 56.3372 -12.2174)
		(property "Reference" "TP59"
			(at 0 0 0)
			(layer "B.SilkS")
			(hide yes)
			(effects
				(font
					(size 1.27 1.27)
				)
				(justify mirror)
			)
		)
		(property "Value" "TPAD32-GP"
			(at 0 -3.166364 0)
			(unlocked yes)
			(layer "B.Fab")
			(hide yes)
			(effects
				(font
					(size 1.016 1.016)
					(thickness 0.1524)
				)
				(justify mirror)
			)
		)
		(property "Device Type" "TPAD32"
			(at 0 -4.690618 0)
			(unlocked yes)
			(layer "B.Fab")
			(hide yes)
			(effects
				(font
					(size 1.016 1.016)
					(thickness 0.1524)
				)
				(justify mirror)
			)
		)
		(duplicate_pad_numbers_are_jumpers no)
		(fp_poly
			(pts
				(arc
					(start 0.7112 0)
					(mid -0.7112 0)
					(end 0.7112 0)
				)
			)
			(stroke
				(width 0)
				(type default)
			)
			(fill no)
			(layer "B.CrtYd")
		)
		(fp_poly
			(pts
				(arc
					(start 0.7112 0)
					(mid -0.7112 0)
					(end 0.7112 0)
				)
			)
			(stroke
				(width 0)
				(type default)
			)
			(fill no)
			(layer "B.Fab")
		)
		(pad "1" smd circle
			(at 0 0 180)
			(size 0.8128 0.8128)
			(layers "B.Cu" "B.Mask" "B.Paste")
			(net "XDP_SOC_CPU_TRST#")
		)
	)
	(footprint ""
		(layer "B.Cu")
		(at 111.379 -70.866)
		(property "Reference" "TP53"
			(at 0 0 0)
			(layer "B.SilkS")
			(hide yes)
			(effects
				(font
					(size 1.27 1.27)
				)
				(justify mirror)
			)
		)
		(property "Value" "TPAD32-GP"
			(at 0 -3.166364 0)
			(unlocked yes)
			(layer "B.Fab")
			(hide yes)
			(effects
				(font
					(size 1.016 1.016)
					(thickness 0.1524)
				)
				(justify mirror)
			)
		)
		(property "Device Type" "TPAD32"
			(at 0 -4.690618 0)
			(unlocked yes)
			(layer "B.Fab")
			(hide yes)
			(effects
				(font
					(size 1.016 1.016)
					(thickness 0.1524)
				)
				(justify mirror)
			)
		)
		(duplicate_pad_numbers_are_jumpers no)
		(fp_poly
			(pts
				(arc
					(start 0.7112 0)
					(mid -0.7112 0)
					(end 0.7112 0)
				)
			)
			(stroke
				(width 0)
				(type default)
			)
			(fill no)
			(layer "B.CrtYd")
		)
		(fp_poly
			(pts
				(arc
					(start 0.7112 0)
					(mid -0.7112 0)
					(end 0.7112 0)
				)
			)
			(stroke
				(width 0)
				(type default)
			)
			(fill no)
			(layer "B.Fab")
		)
		(pad "1" smd circle
			(at 0 0 180)
			(size 0.8128 0.8128)
			(layers "B.Cu" "B.Mask" "B.Paste")
			(net "XDP_SOC_CPU_TMS")
		)
	)
)
